# S9S_MB_2U (Grand Teton) — schematic netlist excerpt (pin names and nets, part order shuffled) for the footprints in the layout excerpt that follows; sources: Cadence DE-HDL packaged netlist, KiCad conversion of 03242023_DA0F0TMBIJ0_F0T_Motherboard_J_brd_V01_OCP.brd

R2381  Q_RES  49.9 1% CHIP  pkg 0402LF  page 266 : A = SVID_CLK0_CPU0_R ; B = PVNN_TERM_CPU0
R3054  Q_RES  33.2 1% CHIP  pkg 0402LF  page 228 : A = PWRGD_PS_PWROK_ME_CONN ; B = PWRGD_PS_PWROK

(kicad_pcb
	(version 20260206)
	(generator "pcbnew")
	(generator_version "10.0")
	(general
		(thickness 1.6)
		(legacy_teardrops no)
	)
	(paper "A4")
	(title_block
		(title "03242023_DA0F0TMBIJ0_F0T_Motherboard_J_brd_V01_OCP.brd")
		(comment 1 "Grand Teton / footprints 2894-2895 of 6105")
	)
	(layers
		(0 "F.Cu" signal "TOP")
		(4 "In1.Cu" signal "GND")
		(6 "In2.Cu" signal "IN1")
		(8 "In3.Cu" signal "GND1")
		(10 "In4.Cu" signal "IN2")
		(12 "In5.Cu" signal "GND2")
		(14 "In6.Cu" signal "IN3")
		(16 "In7.Cu" signal "GND3")
		(18 "In8.Cu" signal "VCC")
		(20 "In9.Cu" signal "VCC1")
		(22 "In10.Cu" signal "GND4")
		(24 "In11.Cu" signal "IN4")
		(26 "In12.Cu" signal "GND5")
		(28 "In13.Cu" signal "IN5")
		(30 "In14.Cu" signal "GND6")
		(32 "In15.Cu" signal "IN6")
		(34 "In16.Cu" signal "GND7")
		(2 "B.Cu" signal "BOTTOM")
		(9 "F.Adhes" user "F.Adhesive")
		(11 "B.Adhes" user "B.Adhesive")
		(13 "F.Paste" user "Package Geometry/Pastemask Top")
		(15 "B.Paste" user "Package Geometry/Pastemask Bottom")
		(5 "F.SilkS" user "Ref Des/Silkscreen Top")
		(7 "B.SilkS" user "Ref Des/Silkscreen Bottom")
		(1 "F.Mask" user "Board Geometry/Soldermask Top")
		(3 "B.Mask" user "Board Geometry/Soldermask Bottom")
		(17 "Dwgs.User" user "User.Drawings")
		(19 "Cmts.User" user "User.Comments")
		(21 "Eco1.User" user "User.Eco1")
		(23 "Eco2.User" user "User.Eco2")
		(25 "Edge.Cuts" user "Board Geometry/Outline")
		(27 "Margin" user)
		(31 "F.CrtYd" user "Package Geometry/Place Bound Top")
		(29 "B.CrtYd" user "Package Geometry/Place Bound Bottom")
		(35 "F.Fab" user "Ref Des/Assembly Top")
		(33 "B.Fab" user "Ref Des/Assembly Bottom")
	)
	(footprint ""
		(layer "F.Cu")
		(at 348.390464 -357.494332 180)
		(property "Reference" "R2381"
			(at 0 0 180)
			(layer "F.SilkS")
			(hide yes)
			(effects
				(font
					(size 1.27 1.27)
				)
			)
		)
		(property "Value" ""
			(at 0 0 180)
			(layer "F.Fab")
			(effects
				(font
					(size 1.27 1.27)
				)
			)
		)
		(duplicate_pad_numbers_are_jumpers no)
		(fp_line
			(start 0.7874 0.4064)
			(end -0.7874 0.4064)
			(stroke
				(width 0.1524)
				(type default)
			)
			(layer "F.SilkS")
		)
		(fp_line
			(start 0.7874 -0.4064)
			(end 0.7874 0.4064)
			(stroke
				(width 0.1524)
				(type default)
			)
			(layer "F.SilkS")
		)
		(fp_line
			(start -0.7874 0.4064)
			(end -0.7874 -0.4064)
			(stroke
				(width 0.1524)
				(type default)
			)
			(layer "F.SilkS")
		)
		(fp_line
			(start -0.7874 -0.4064)
			(end 0.7874 -0.4064)
			(stroke
				(width 0.1524)
				(type default)
			)
			(layer "F.SilkS")
		)
		(fp_line
			(start 0.67945 0.3048)
			(end 0.120396 0.3048)
			(stroke
				(width 0.1)
				(type default)
			)
			(layer "F.Fab")
		)
		(fp_line
			(start 0.67945 -0.3048)
			(end 0.67945 0.3048)
			(stroke
				(width 0.1)
				(type default)
			)
			(layer "F.Fab")
		)
		(fp_line
			(start 0.12065 -0.2794)
			(end 0.12065 -0.3048)
			(stroke
				(width 0.1)
				(type default)
			)
			(layer "F.Fab")
		)
		(fp_line
			(start 0.12065 -0.3048)
			(end 0.67945 -0.3048)
			(stroke
				(width 0.1)
				(type default)
			)
			(layer "F.Fab")
		)
		(fp_line
			(start 0.120396 0.3048)
			(end 0.120396 0.2794)
			(stroke
				(width 0.1)
				(type default)
			)
			(layer "F.Fab")
		)
		(fp_line
			(start 0.120396 0.2794)
			(end -0.12065 0.2794)
			(stroke
				(width 0.1)
				(type default)
			)
			(layer "F.Fab")
		)
		(fp_line
			(start -0.12065 0.3048)
			(end -0.67945 0.3048)
			(stroke
				(width 0.1)
				(type default)
			)
			(layer "F.Fab")
		)
		(fp_line
			(start -0.12065 0.2794)
			(end -0.12065 0.3048)
			(stroke
				(width 0.1)
				(type default)
			)
			(layer "F.Fab")
		)
		(fp_line
			(start -0.12065 -0.2794)
			(end 0.12065 -0.2794)
			(stroke
				(width 0.1)
				(type default)
			)
			(layer "F.Fab")
		)
		(fp_line
			(start -0.12065 -0.305054)
			(end -0.12065 -0.2794)
			(stroke
				(width 0.1)
				(type default)
			)
			(layer "F.Fab")
		)
		(fp_line
			(start -0.67945 0.3048)
			(end -0.67945 -0.305054)
			(stroke
				(width 0.1)
				(type default)
			)
			(layer "F.Fab")
		)
		(fp_line
			(start -0.67945 -0.305054)
			(end -0.12065 -0.305054)
			(stroke
				(width 0.1)
				(type default)
			)
			(layer "F.Fab")
		)
		(pad "1" smd circle
			(at -0.40005 0 180)
			(size 0 0)
			(layers "F.Cu" "F.Mask" "F.Paste")
			(net "SVID_CLK0_CPU0_R")
		)
		(pad "2" smd circle
			(at 0.40005 0 180)
			(size 0 0)
			(layers "F.Cu" "F.Mask" "F.Paste")
			(net "PVNN_TERM_CPU0")
		)
	)
	(footprint ""
		(layer "F.Cu")
		(at 28.08605 -47.335948)
		(property "Reference" "R3054"
			(at 0 0 0)
			(layer "F.SilkS")
			(hide yes)
			(effects
				(font
					(size 1.27 1.27)
				)
			)
		)
		(property "Value" ""
			(at 0 0 0)
			(layer "F.Fab")
			(effects
				(font
					(size 1.27 1.27)
				)
			)
		)
		(duplicate_pad_numbers_are_jumpers no)
		(fp_line
			(start -0.7874 -0.4064)
			(end 0.7874 -0.4064)
			(stroke
				(width 0.1524)
				(type default)
			)
			(layer "F.SilkS")
		)
		(fp_line
			(start -0.7874 0.4064)
			(end -0.7874 -0.4064)
			(stroke
				(width 0.1524)
				(type default)
			)
			(layer "F.SilkS")
		)
		(fp_line
			(start 0.7874 -0.4064)
			(end 0.7874 0.4064)
			(stroke
				(width 0.1524)
				(type default)
			)
			(layer "F.SilkS")
		)
		(fp_line
			(start 0.7874 0.4064)
			(end -0.7874 0.4064)
			(stroke
				(width 0.1524)
				(type default)
			)
			(layer "F.SilkS")
		)
		(fp_line
			(start -0.67945 -0.305054)
			(end -0.12065 -0.305054)
			(stroke
				(width 0.1)
				(type default)
			)
			(layer "F.Fab")
		)
		(fp_line
			(start -0.67945 0.3048)
			(end -0.67945 -0.305054)
			(stroke
				(width 0.1)
				(type default)
			)
			(layer "F.Fab")
		)
		(fp_line
			(start -0.12065 -0.305054)
			(end -0.12065 -0.2794)
			(stroke
				(width 0.1)
				(type default)
			)
			(layer "F.Fab")
		)
		(fp_line
			(start -0.12065 -0.2794)
			(end 0.12065 -0.2794)
			(stroke
				(width 0.1)
				(type default)
			)
			(layer "F.Fab")
		)
		(fp_line
			(start -0.12065 0.2794)
			(end -0.12065 0.3048)
			(stroke
				(width 0.1)
				(type default)
			)
			(layer "F.Fab")
		)
		(fp_line
			(start -0.12065 0.3048)
			(end -0.67945 0.3048)
			(stroke
				(width 0.1)
				(type default)
			)
			(layer "F.Fab")
		)
		(fp_line
			(start 0.120396 0.2794)
			(end -0.12065 0.2794)
			(stroke
				(width 0.1)
				(type default)
			)
			(layer "F.Fab")
		)
		(fp_line
			(start 0.120396 0.3048)
			(end 0.120396 0.2794)
			(stroke
				(width 0.1)
				(type default)
			)
			(layer "F.Fab")
		)
		(fp_line
			(start 0.12065 -0.3048)
			(end 0.67945 -0.3048)
			(stroke
				(width 0.1)
				(type default)
			)
			(layer "F.Fab")
		)
		(fp_line
			(start 0.12065 -0.2794)
			(end 0.12065 -0.3048)
			(stroke
				(width 0.1)
				(type default)
			)
			(layer "F.Fab")
		)
		(fp_line
			(start 0.67945 -0.3048)
			(end 0.67945 0.3048)
			(stroke
				(width 0.1)
				(type default)
			)
			(layer "F.Fab")
		)
		(fp_line
			(start 0.67945 0.3048)
			(end 0.120396 0.3048)
			(stroke
				(width 0.1)
				(type default)
			)
			(layer "F.Fab")
		)
		(pad "1" smd circle
			(at -0.40005 0)
			(size 0 0)
			(layers "F.Cu" "F.Mask" "F.Paste")
			(net "PWRGD_PS_PWROK_ME_CONN")
		)
		(pad "2" smd circle
			(at 0.40005 0)
			(size 0 0)
			(layers "F.Cu" "F.Mask" "F.Paste")
			(net "PWRGD_PS_PWROK")
		)
	)
)
